FILE_TYPE = CONNECTIVITY;
{Allegro Design Entry HDL 17.2-2016 S081 (4005846) 1/11/2022}
"PAGE_NUMBER" = 35;
0"NC";
1"GND\g";
%"SOCKET4677_AZIF0045P001C01CS"
"25","(650,2600)","0","pure_quanta","I102";
;
PART_NUMBER"DGA^7000023"
MATERIAL"IO"
PART_TYPE"SMLF"
VALUE"SOCKET4677_AZIF0045-P001C01CS"
$LOCATION"U2"
CDS_LMAN_SYM_OUTLINE"-1050,1350,1050,-1350"
NEEDS_NO_SIZE"TRUE"
CDS_LIB"pure_quanta"
CDS_LOCATION"U2"
$SEC"25"
CDS_SEC"25";
"UPI3_TX_DP0"
$PN"EK85"0;
"UPI3_TX_DP1"
$PN"EM85"0;
"UPI3_TX_DP2"
$PN"EN86"0;
"UPI3_TX_DP3"
$PN"EP87"0;
"UPI3_TX_DP4"
$PN"EH87"0;
"UPI3_TX_DP5"
$PN"EL88"0;
"UPI3_TX_DP6"
$PN"DT81"0;
"UPI3_TX_DP7"
$PN"DU82"0;
"UPI3_TX_DP8"
$PN"DR80"0;
"UPI3_TX_DP9"
$PN"DP83"0;
"UPI3_TX_DP10"
$PN"DL82"0;
"UPI3_TX_DP11"
$PN"DN80"0;
"UPI3_TX_DP12"
$PN"DA76"0;
"UPI3_TX_DP13"
$PN"CV77"0;
"UPI3_TX_DP14"
$PN"CR76"0;
"UPI3_TX_DP15"
$PN"CU74"0;
"UPI3_TX_DP16"
$PN"CM77"0;
"UPI3_TX_DP17"
$PN"CJ78"0;
"UPI3_TX_DP18"
$PN"CL76"0;
"UPI3_TX_DP19"
$PN"CF77"0;
"UPI3_TX_DP20"
$PN"CH75"0;
"UPI3_TX_DP21"
$PN"CK75"0;
"UPI3_TX_DP22"
$PN"CW74"0;
"UPI3_TX_DP23"
$PN"CD73"0;
"UPI3_TX_DN0"
$PN"EH85"0;
"UPI3_TX_DN1"
$PN"EL84"0;
"UPI3_TX_DN2"
$PN"EP85"0;
"UPI3_TX_DN3"
$PN"EM87"0;
"UPI3_TX_DN4"
$PN"EJ86"0;
"UPI3_TX_DN5"
$PN"EK87"0;
"UPI3_TX_DN6"
$PN"DU80"0;
"UPI3_TX_DN7"
$PN"DR82"0;
"UPI3_TX_DN8"
$PN"DP79"0;
"UPI3_TX_DN9"
$PN"DN82"0;
"UPI3_TX_DN10"
$PN"DM81"0;
"UPI3_TX_DN11"
$PN"DL80"0;
"UPI3_TX_DN12"
$PN"CW76"0;
"UPI3_TX_DN13"
$PN"CU76"0;
"UPI3_TX_DN14"
$PN"CT75"0;
"UPI3_TX_DN15"
$PN"CR74"0;
"UPI3_TX_DN16"
$PN"CK77"0;
"UPI3_TX_DN17"
$PN"CH77"0;
"UPI3_TX_DN18"
$PN"CM75"0;
"UPI3_TX_DN19"
$PN"CG76"0;
"UPI3_TX_DN20"
$PN"CF75"0;
"UPI3_TX_DN21"
$PN"CJ74"0;
"UPI3_TX_DN22"
$PN"CV73"0;
"UPI3_TX_DN23"
$PN"CF73"0;
"UPI3_RX_DP0"
$PN"EL80"1;
"UPI3_RX_DP1"
$PN"ER82"1;
"UPI3_RX_DP2"
$PN"EN82"1;
"UPI3_RX_DP3"
$PN"EJ82"1;
"UPI3_RX_DP4"
$PN"EE82"1;
"UPI3_RX_DP5"
$PN"EF83"1;
"UPI3_RX_DP6"
$PN"ED81"1;
"UPI3_RX_DP7"
$PN"DY83"1;
"UPI3_RX_DP8"
$PN"EB81"1;
"UPI3_RX_DP9"
$PN"DL78"1;
"UPI3_RX_DP10"
$PN"DH79"1;
"UPI3_RX_DP11"
$PN"DG82"1;
"UPI3_RX_DP12"
$PN"DH83"1;
"UPI3_RX_DP13"
$PN"DF81"1;
"UPI3_RX_DP14"
$PN"DB83"1;
"UPI3_RX_DP15"
$PN"DD81"1;
"UPI3_RX_DP16"
$PN"DE78"1;
"UPI3_RX_DP17"
$PN"CW82"1;
"UPI3_RX_DP18"
$PN"CT83"1;
"UPI3_RX_DP19"
$PN"CV81"1;
"UPI3_RX_DP20"
$PN"CN82"1;
"UPI3_RX_DP21"
$PN"CR80"1;
"UPI3_RX_DP22"
$PN"CU80"1;
"UPI3_RX_DP23"
$PN"DB79"1;
"UPI3_RX_DN0"
$PN"EJ80"1;
"UPI3_RX_DN1"
$PN"EP81"1;
"UPI3_RX_DN2"
$PN"EL82"1;
"UPI3_RX_DN3"
$PN"EK81"1;
"UPI3_RX_DN4"
$PN"EF81"1;
"UPI3_RX_DN5"
$PN"ED83"1;
"UPI3_RX_DN6"
$PN"EC80"1;
"UPI3_RX_DN7"
$PN"EA82"1;
"UPI3_RX_DN8"
$PN"DY81"1;
"UPI3_RX_DN9"
$PN"DJ78"1;
"UPI3_RX_DN10"
$PN"DG78"1;
"UPI3_RX_DN11"
$PN"DH81"1;
"UPI3_RX_DN12"
$PN"DF83"1;
"UPI3_RX_DN13"
$PN"DE80"1;
"UPI3_RX_DN14"
$PN"DC82"1;
"UPI3_RX_DN15"
$PN"DB81"1;
"UPI3_RX_DN16"
$PN"DF77"1;
"UPI3_RX_DN17"
$PN"CU82"1;
"UPI3_RX_DN18"
$PN"CR82"1;
"UPI3_RX_DN19"
$PN"CW80"1;
"UPI3_RX_DN20"
$PN"CP81"1;
"UPI3_RX_DN21"
$PN"CN80"1;
"UPI3_RX_DN22"
$PN"CT79"1;
"UPI3_RX_DN23"
$PN"DA78"1;
%"UNIVERSAL_GND"
"1","(-850,1075)","0","logical_power","I104";
;
CDS_LIB"logical_power"
HDL_POWER"GND";
"A"1;
END.
